(kicad_pcb
	(version 20260206)
	(generator "pcbnew")
	(generator_version "10.0")
	(general
		(thickness 1.6)
		(legacy_teardrops no)
	)
	(paper "A4")
	(title_block
		(title "panther-plus-userver — 13130-1b_20150205.brd")
		(comment 1 "Honey Badger (Wiwynn) / footprint 1214 of 1509 (DIMM3), pads 198-204 of 210")
	)
	(layers
		(0 "F.Cu" signal "TOP")
		(4 "In1.Cu" signal "L2")
		(6 "In2.Cu" signal "L3")
		(8 "In3.Cu" signal "L4")
		(10 "In4.Cu" signal "L5")
		(12 "In5.Cu" signal "L6")
		(14 "In6.Cu" signal "L7")
		(16 "In7.Cu" signal "L8")
		(18 "In8.Cu" signal "L9")
		(20 "In9.Cu" signal "L10")
		(22 "In10.Cu" signal "L11")
		(2 "B.Cu" signal "BOTTOM")
		(9 "F.Adhes" user "F.Adhesive")
		(11 "B.Adhes" user "B.Adhesive")
		(13 "F.Paste" user "Package Geometry/Pastemask Top")
		(15 "B.Paste" user "Package Geometry/Pastemask Bottom")
		(5 "F.SilkS" user "Ref Des/Silkscreen Top")
		(7 "B.SilkS" user "Ref Des/Silkscreen Bottom")
		(1 "F.Mask" user "Board Geometry/Soldermask Top")
		(3 "B.Mask" user "Board Geometry/Soldermask Bottom")
		(17 "Dwgs.User" user "User.Drawings")
		(19 "Cmts.User" user "User.Comments")
		(21 "Eco1.User" user "User.Eco1")
		(23 "Eco2.User" user "User.Eco2")
		(25 "Edge.Cuts" user "Board Geometry/Outline")
		(27 "Margin" user)
		(31 "F.CrtYd" user "Package Geometry/Place Bound Top")
		(29 "B.CrtYd" user "Package Geometry/Place Bound Bottom")
		(35 "F.Fab" user "Ref Des/Assembly Top")
		(33 "B.Fab" user "Ref Des/Assembly Bottom")
	)
	(footprint ""
		(layer "B.Cu")
		(at 159.999934 -5.790692)
		(property "Reference" "DIMM3"
			(at 0 0 0)
			(layer "B.SilkS")
			(hide yes)
			(effects
				(font
					(size 1.27 1.27)
				)
				(justify mirror)
			)
		)
		(property "Value" "DDR3-204P-142-COLAY-1-GP-U"
			(at 41.312338 -16.676878 0)
			(unlocked yes)
			(layer "B.Fab")
			(hide yes)
			(effects
				(font
					(size 1.016 1.016)
					(thickness 0.1524)
				)
				(justify mirror)
			)
		)
		(property "Device Type" "AS0A626-J8R6-7H-COLAY-1"
			(at 41.312338 -18.200878 0)
			(unlocked yes)
			(layer "B.Fab")
			(hide yes)
			(effects
				(font
					(size 1.016 1.016)
					(thickness 0.1524)
				)
				(justify mirror)
			)
		)
		(duplicate_pad_numbers_are_jumpers no)
		(pad "196" smd custom
			(at 29.249878 4.100068 180)
			(size 0.1143 0.1143)
			(layers "B.Cu" "B.Mask" "B.Paste")
			(net "GND")
			(options
				(clearance outline)
				(anchor circle)
			)
			(primitives
				(gr_poly
					(pts
						(xy 0 -0.9017) (xy -0.03175 -0.89916) (xy -0.0635 -0.889) (xy -0.09144 -0.87376) (xy -0.11684 -0.85344)
						(xy -0.13716 -0.82804) (xy -0.1524 -0.8001) (xy -0.16256 -0.76835) (xy -0.1651 -0.7366) (xy -0.1651 -0.11938)
						(xy -0.17272 -0.11176) (xy -0.19812 -0.0762) (xy -0.2032 -0.06604) (xy -0.20701 -0.05715) (xy -0.21209 -0.04699)
						(xy -0.2159 -0.03683) (xy -0.21844 -0.02667) (xy -0.22225 -0.01524) (xy -0.22352 -0.00508) (xy -0.22606 0.00508)
						(xy -0.22733 0.01651) (xy -0.22733 0.02667) (xy -0.2286 0.0381) (xy -0.22733 0.04953) (xy -0.22733 0.05969)
						(xy -0.22606 0.07112) (xy -0.22352 0.08128) (xy -0.22225 0.09144) (xy -0.21844 0.10287) (xy -0.2159 0.11303)
						(xy -0.21209 0.12319) (xy -0.20701 0.13335) (xy -0.2032 0.14224) (xy -0.19812 0.1524) (xy -0.17272 0.18796)
						(xy -0.1651 0.19558) (xy -0.1651 0.7366) (xy -0.16256 0.76835) (xy -0.1524 0.8001) (xy -0.13716 0.82804)
						(xy -0.11684 0.85344) (xy -0.09144 0.87376) (xy -0.0635 0.889) (xy -0.03175 0.89916) (xy 0 0.9017)
						(xy 0.03175 0.89916) (xy 0.0635 0.889) (xy 0.09144 0.87376) (xy 0.11684 0.85344) (xy 0.13716 0.82804)
						(xy 0.1524 0.8001) (xy 0.16256 0.76835) (xy 0.1651 0.7366) (xy 0.1651 0.19685) (xy 0.17272 0.18923)
						(xy 0.17907 0.18034) (xy 0.18669 0.17145) (xy 0.19177 0.16256) (xy 0.19812 0.15367) (xy 0.20828 0.13335)
						(xy 0.21971 0.10287) (xy 0.22225 0.09271) (xy 0.22479 0.08128) (xy 0.22606 0.07112) (xy 0.2286 0.05969)
						(xy 0.2286 0.01651) (xy 0.22606 0.00508) (xy 0.22479 -0.00508) (xy 0.22225 -0.01651) (xy 0.21971 -0.02667)
						(xy 0.20828 -0.05715) (xy 0.19812 -0.07747) (xy 0.19177 -0.08636) (xy 0.18669 -0.09525) (xy 0.17907 -0.10414)
						(xy 0.17272 -0.11303) (xy 0.1651 -0.12065) (xy 0.1651 -0.7366) (xy 0.16256 -0.76835) (xy 0.1524 -0.8001)
						(xy 0.13716 -0.82804) (xy 0.11684 -0.85344) (xy 0.09144 -0.87376) (xy 0.0635 -0.889) (xy 0.03175 -0.89916)
					)
					(width 0)
					(fill yes)
				)
			)
		)
		(pad "197" smd custom
			(at 29.550106 -4.100068 180)
			(size 0.1143 0.1143)
			(layers "B.Cu" "B.Mask" "B.Paste")
			(net "CHB_0_SA0")
			(options
				(clearance outline)
				(anchor circle)
			)
			(primitives
				(gr_poly
					(pts
						(xy 0 -0.9017) (xy -0.03175 -0.89916) (xy -0.0635 -0.889) (xy -0.09144 -0.87376) (xy -0.11684 -0.85344)
						(xy -0.13716 -0.82804) (xy -0.1524 -0.8001) (xy -0.16256 -0.76835) (xy -0.1651 -0.7366) (xy -0.1651 -0.44958)
						(xy -0.17272 -0.44196) (xy -0.19812 -0.4064) (xy -0.2032 -0.39624) (xy -0.20701 -0.38735) (xy -0.21209 -0.37719)
						(xy -0.2159 -0.36703) (xy -0.21844 -0.35687) (xy -0.22225 -0.34544) (xy -0.22352 -0.33528) (xy -0.22606 -0.32512)
						(xy -0.22733 -0.31369) (xy -0.22733 -0.30353) (xy -0.2286 -0.2921) (xy -0.22733 -0.28067) (xy -0.22733 -0.27051)
						(xy -0.22606 -0.25908) (xy -0.22352 -0.24892) (xy -0.22225 -0.23876) (xy -0.21844 -0.22733) (xy -0.2159 -0.21717)
						(xy -0.21209 -0.20701) (xy -0.20701 -0.19685) (xy -0.2032 -0.18796) (xy -0.19812 -0.1778) (xy -0.17272 -0.14224)
						(xy -0.1651 -0.13462) (xy -0.1651 0.7366) (xy -0.16256 0.76835) (xy -0.1524 0.8001) (xy -0.13716 0.82804)
						(xy -0.11684 0.85344) (xy -0.09144 0.87376) (xy -0.0635 0.889) (xy -0.03175 0.89916) (xy 0 0.9017)
						(xy 0.03175 0.89916) (xy 0.0635 0.889) (xy 0.09144 0.87376) (xy 0.11684 0.85344) (xy 0.13716 0.82804)
						(xy 0.1524 0.8001) (xy 0.16256 0.76835) (xy 0.1651 0.7366) (xy 0.1651 -0.13462) (xy 0.17272 -0.14224)
						(xy 0.19812 -0.1778) (xy 0.2032 -0.18796) (xy 0.20701 -0.19685) (xy 0.21209 -0.20701) (xy 0.2159 -0.21717)
						(xy 0.21844 -0.22733) (xy 0.22225 -0.23876) (xy 0.22352 -0.24892) (xy 0.22606 -0.25908) (xy 0.22733 -0.27051)
						(xy 0.22733 -0.28067) (xy 0.2286 -0.2921) (xy 0.22733 -0.30353) (xy 0.22733 -0.31369) (xy 0.22606 -0.32512)
						(xy 0.22352 -0.33528) (xy 0.22225 -0.34544) (xy 0.21844 -0.35687) (xy 0.2159 -0.36703) (xy 0.21209 -0.37719)
						(xy 0.20701 -0.38735) (xy 0.2032 -0.39624) (xy 0.19812 -0.4064) (xy 0.17272 -0.44196) (xy 0.1651 -0.44958)
						(xy 0.1651 -0.7366) (xy 0.16256 -0.76835) (xy 0.1524 -0.8001) (xy 0.13716 -0.82804) (xy 0.11684 -0.85344)
						(xy 0.09144 -0.87376) (xy 0.0635 -0.889) (xy 0.03175 -0.89916)
					)
					(width 0)
					(fill yes)
				)
			)
		)
		(pad "198" smd custom
			(at 29.85008 4.100068 180)
			(size 0.1143 0.1143)
			(layers "B.Cu" "B.Mask" "B.Paste")
			(net "MEMORY_HOT_LV_R#")
			(options
				(clearance outline)
				(anchor circle)
			)
			(primitives
				(gr_poly
					(pts
						(xy 0 -0.9017) (xy -0.03175 -0.89916) (xy -0.0635 -0.889) (xy -0.09144 -0.87376) (xy -0.11684 -0.85344)
						(xy -0.13716 -0.82804) (xy -0.1524 -0.8001) (xy -0.16256 -0.76835) (xy -0.1651 -0.7366) (xy -0.1651 0.13462)
						(xy -0.17272 0.14224) (xy -0.19812 0.1778) (xy -0.2032 0.18796) (xy -0.20701 0.19685) (xy -0.21209 0.20701)
						(xy -0.2159 0.21717) (xy -0.21844 0.22733) (xy -0.22225 0.23876) (xy -0.22352 0.24892) (xy -0.22606 0.25908)
						(xy -0.22733 0.27051) (xy -0.22733 0.28067) (xy -0.2286 0.2921) (xy -0.22733 0.30353) (xy -0.22733 0.31369)
						(xy -0.22606 0.32512) (xy -0.22352 0.33528) (xy -0.22225 0.34544) (xy -0.21844 0.35687) (xy -0.2159 0.36703)
						(xy -0.21209 0.37719) (xy -0.20701 0.38735) (xy -0.2032 0.39624) (xy -0.19812 0.4064) (xy -0.17272 0.44196)
						(xy -0.1651 0.44958) (xy -0.1651 0.7366) (xy -0.16256 0.76835) (xy -0.1524 0.8001) (xy -0.13716 0.82804)
						(xy -0.11684 0.85344) (xy -0.09144 0.87376) (xy -0.0635 0.889) (xy -0.03175 0.89916) (xy 0 0.9017)
						(xy 0.03175 0.89916) (xy 0.0635 0.889) (xy 0.09144 0.87376) (xy 0.11684 0.85344) (xy 0.13716 0.82804)
						(xy 0.1524 0.8001) (xy 0.16256 0.76835) (xy 0.1651 0.7366) (xy 0.1651 0.44958) (xy 0.17272 0.44196)
						(xy 0.19812 0.4064) (xy 0.2032 0.39624) (xy 0.20701 0.38735) (xy 0.21209 0.37719) (xy 0.2159 0.36703)
						(xy 0.21844 0.35687) (xy 0.22225 0.34544) (xy 0.22352 0.33528) (xy 0.22606 0.32512) (xy 0.22733 0.31369)
						(xy 0.22733 0.30353) (xy 0.2286 0.2921) (xy 0.22733 0.28067) (xy 0.22733 0.27051) (xy 0.22606 0.25908)
						(xy 0.22352 0.24892) (xy 0.22225 0.23876) (xy 0.21844 0.22733) (xy 0.2159 0.21717) (xy 0.21209 0.20701)
						(xy 0.20701 0.19685) (xy 0.2032 0.18796) (xy 0.19812 0.1778) (xy 0.17272 0.14224) (xy 0.1651 0.13462)
						(xy 0.1651 -0.7366) (xy 0.16256 -0.76835) (xy 0.1524 -0.8001) (xy 0.13716 -0.82804) (xy 0.11684 -0.85344)
						(xy 0.09144 -0.87376) (xy 0.0635 -0.889) (xy 0.03175 -0.89916)
					)
					(width 0)
					(fill yes)
				)
			)
		)
		(pad "199" smd custom
			(at 30.150054 -4.100068 180)
			(size 0.1143 0.1143)
			(layers "B.Cu" "B.Mask" "B.Paste")
			(net "P3V3_STBY")
			(options
				(clearance outline)
				(anchor circle)
			)
			(primitives
				(gr_poly
					(pts
						(xy 0 -0.9017) (xy -0.03175 -0.89916) (xy -0.0635 -0.889) (xy -0.09144 -0.87376) (xy -0.11684 -0.85344)
						(xy -0.13716 -0.82804) (xy -0.1524 -0.8001) (xy -0.16256 -0.76835) (xy -0.1651 -0.7366) (xy -0.1651 -0.19685)
						(xy -0.17272 -0.18923) (xy -0.17907 -0.18034) (xy -0.18669 -0.17145) (xy -0.19177 -0.16256) (xy -0.19812 -0.15367)
						(xy -0.20828 -0.13335) (xy -0.21971 -0.10287) (xy -0.22225 -0.09271) (xy -0.22479 -0.08128) (xy -0.22606 -0.07112)
						(xy -0.2286 -0.05969) (xy -0.2286 -0.01651) (xy -0.22606 -0.00508) (xy -0.22479 0.00508) (xy -0.22225 0.01651)
						(xy -0.21971 0.02667) (xy -0.20828 0.05715) (xy -0.19812 0.07747) (xy -0.19177 0.08636) (xy -0.18669 0.09525)
						(xy -0.17907 0.10414) (xy -0.17272 0.11303) (xy -0.1651 0.12065) (xy -0.1651 0.7366) (xy -0.16256 0.76835)
						(xy -0.1524 0.8001) (xy -0.13716 0.82804) (xy -0.11684 0.85344) (xy -0.09144 0.87376) (xy -0.0635 0.889)
						(xy -0.03175 0.89916) (xy 0 0.9017) (xy 0.03175 0.89916) (xy 0.0635 0.889) (xy 0.09144 0.87376)
						(xy 0.11684 0.85344) (xy 0.13716 0.82804) (xy 0.1524 0.8001) (xy 0.16256 0.76835) (xy 0.1651 0.7366)
						(xy 0.1651 0.11938) (xy 0.17272 0.11176) (xy 0.19812 0.0762) (xy 0.2032 0.06604) (xy 0.20701 0.05715)
						(xy 0.21209 0.04699) (xy 0.2159 0.03683) (xy 0.21844 0.02667) (xy 0.22225 0.01524) (xy 0.22352 0.00508)
						(xy 0.22606 -0.00508) (xy 0.22733 -0.01651) (xy 0.22733 -0.02667) (xy 0.2286 -0.0381) (xy 0.22733 -0.04953)
						(xy 0.22733 -0.05969) (xy 0.22606 -0.07112) (xy 0.22352 -0.08128) (xy 0.22225 -0.09144) (xy 0.21844 -0.10287)
						(xy 0.2159 -0.11303) (xy 0.21209 -0.12319) (xy 0.20701 -0.13335) (xy 0.2032 -0.14224) (xy 0.19812 -0.1524)
						(xy 0.17272 -0.18796) (xy 0.1651 -0.19558) (xy 0.1651 -0.7366) (xy 0.16256 -0.76835) (xy 0.1524 -0.8001)
						(xy 0.13716 -0.82804) (xy 0.11684 -0.85344) (xy 0.09144 -0.87376) (xy 0.0635 -0.889) (xy 0.03175 -0.89916)
					)
					(width 0)
					(fill yes)
				)
			)
		)
		(pad "200" smd custom
			(at 30.450028 4.100068 180)
			(size 0.1143 0.1143)
			(layers "B.Cu" "B.Mask" "B.Paste")
			(net "SMB_M_B0_R_DATA")
			(options
				(clearance outline)
				(anchor circle)
			)
			(primitives
				(gr_poly
					(pts
						(xy 0 -0.9017) (xy -0.03175 -0.89916) (xy -0.0635 -0.889) (xy -0.09144 -0.87376) (xy -0.11684 -0.85344)
						(xy -0.13716 -0.82804) (xy -0.1524 -0.8001) (xy -0.16256 -0.76835) (xy -0.1651 -0.7366) (xy -0.1651 -0.11938)
						(xy -0.17272 -0.11176) (xy -0.19812 -0.0762) (xy -0.2032 -0.06604) (xy -0.20701 -0.05715) (xy -0.21209 -0.04699)
						(xy -0.2159 -0.03683) (xy -0.21844 -0.02667) (xy -0.22225 -0.01524) (xy -0.22352 -0.00508) (xy -0.22606 0.00508)
						(xy -0.22733 0.01651) (xy -0.22733 0.02667) (xy -0.2286 0.0381) (xy -0.22733 0.04953) (xy -0.22733 0.05969)
						(xy -0.22606 0.07112) (xy -0.22352 0.08128) (xy -0.22225 0.09144) (xy -0.21844 0.10287) (xy -0.2159 0.11303)
						(xy -0.21209 0.12319) (xy -0.20701 0.13335) (xy -0.2032 0.14224) (xy -0.19812 0.1524) (xy -0.17272 0.18796)
						(xy -0.1651 0.19558) (xy -0.1651 0.7366) (xy -0.16256 0.76835) (xy -0.1524 0.8001) (xy -0.13716 0.82804)
						(xy -0.11684 0.85344) (xy -0.09144 0.87376) (xy -0.0635 0.889) (xy -0.03175 0.89916) (xy 0 0.9017)
						(xy 0.03175 0.89916) (xy 0.0635 0.889) (xy 0.09144 0.87376) (xy 0.11684 0.85344) (xy 0.13716 0.82804)
						(xy 0.1524 0.8001) (xy 0.16256 0.76835) (xy 0.1651 0.7366) (xy 0.1651 0.19685) (xy 0.17272 0.18923)
						(xy 0.17907 0.18034) (xy 0.18669 0.17145) (xy 0.19177 0.16256) (xy 0.19812 0.15367) (xy 0.20828 0.13335)
						(xy 0.21971 0.10287) (xy 0.22225 0.09271) (xy 0.22479 0.08128) (xy 0.22606 0.07112) (xy 0.2286 0.05969)
						(xy 0.2286 0.01651) (xy 0.22606 0.00508) (xy 0.22479 -0.00508) (xy 0.22225 -0.01651) (xy 0.21971 -0.02667)
						(xy 0.20828 -0.05715) (xy 0.19812 -0.07747) (xy 0.19177 -0.08636) (xy 0.18669 -0.09525) (xy 0.17907 -0.10414)
						(xy 0.17272 -0.11303) (xy 0.1651 -0.12065) (xy 0.1651 -0.7366) (xy 0.16256 -0.76835) (xy 0.1524 -0.8001)
						(xy 0.13716 -0.82804) (xy 0.11684 -0.85344) (xy 0.09144 -0.87376) (xy 0.0635 -0.889) (xy 0.03175 -0.89916)
					)
					(width 0)
					(fill yes)
				)
			)
		)
		(pad "201" smd custom
			(at 30.750002 -4.100068 180)
			(size 0.1143 0.1143)
			(layers "B.Cu" "B.Mask" "B.Paste")
			(net "CHB_0_SA1")
			(options
				(clearance outline)
				(anchor circle)
			)
			(primitives
				(gr_poly
					(pts
						(xy 0 -0.9017) (xy -0.03175 -0.89916) (xy -0.0635 -0.889) (xy -0.09144 -0.87376) (xy -0.11684 -0.85344)
						(xy -0.13716 -0.82804) (xy -0.1524 -0.8001) (xy -0.16256 -0.76835) (xy -0.1651 -0.7366) (xy -0.1651 -0.44958)
						(xy -0.17272 -0.44196) (xy -0.19812 -0.4064) (xy -0.2032 -0.39624) (xy -0.20701 -0.38735) (xy -0.21209 -0.37719)
						(xy -0.2159 -0.36703) (xy -0.21844 -0.35687) (xy -0.22225 -0.34544) (xy -0.22352 -0.33528) (xy -0.22606 -0.32512)
						(xy -0.22733 -0.31369) (xy -0.22733 -0.30353) (xy -0.2286 -0.2921) (xy -0.22733 -0.28067) (xy -0.22733 -0.27051)
						(xy -0.22606 -0.25908) (xy -0.22352 -0.24892) (xy -0.22225 -0.23876) (xy -0.21844 -0.22733) (xy -0.2159 -0.21717)
						(xy -0.21209 -0.20701) (xy -0.20701 -0.19685) (xy -0.2032 -0.18796) (xy -0.19812 -0.1778) (xy -0.17272 -0.14224)
						(xy -0.1651 -0.13462) (xy -0.1651 0.7366) (xy -0.16256 0.76835) (xy -0.1524 0.8001) (xy -0.13716 0.82804)
						(xy -0.11684 0.85344) (xy -0.09144 0.87376) (xy -0.0635 0.889) (xy -0.03175 0.89916) (xy 0 0.9017)
						(xy 0.03175 0.89916) (xy 0.0635 0.889) (xy 0.09144 0.87376) (xy 0.11684 0.85344) (xy 0.13716 0.82804)
						(xy 0.1524 0.8001) (xy 0.16256 0.76835) (xy 0.1651 0.7366) (xy 0.1651 -0.13462) (xy 0.17272 -0.14224)
						(xy 0.19812 -0.1778) (xy 0.2032 -0.18796) (xy 0.20701 -0.19685) (xy 0.21209 -0.20701) (xy 0.2159 -0.21717)
						(xy 0.21844 -0.22733) (xy 0.22225 -0.23876) (xy 0.22352 -0.24892) (xy 0.22606 -0.25908) (xy 0.22733 -0.27051)
						(xy 0.22733 -0.28067) (xy 0.2286 -0.2921) (xy 0.22733 -0.30353) (xy 0.22733 -0.31369) (xy 0.22606 -0.32512)
						(xy 0.22352 -0.33528) (xy 0.22225 -0.34544) (xy 0.21844 -0.35687) (xy 0.2159 -0.36703) (xy 0.21209 -0.37719)
						(xy 0.20701 -0.38735) (xy 0.2032 -0.39624) (xy 0.19812 -0.4064) (xy 0.17272 -0.44196) (xy 0.1651 -0.44958)
						(xy 0.1651 -0.7366) (xy 0.16256 -0.76835) (xy 0.1524 -0.8001) (xy 0.13716 -0.82804) (xy 0.11684 -0.85344)
						(xy 0.09144 -0.87376) (xy 0.0635 -0.889) (xy 0.03175 -0.89916)
					)
					(width 0)
					(fill yes)
				)
			)
		)
		(pad "202" smd custom
			(at 31.049976 4.100068 180)
			(size 0.1143 0.1143)
			(layers "B.Cu" "B.Mask" "B.Paste")
			(net "SMB_M_B0_R_CLK")
			(options
				(clearance outline)
				(anchor circle)
			)
			(primitives
				(gr_poly
					(pts
						(xy 0 -0.9017) (xy -0.03175 -0.89916) (xy -0.0635 -0.889) (xy -0.09144 -0.87376) (xy -0.11684 -0.85344)
						(xy -0.13716 -0.82804) (xy -0.1524 -0.8001) (xy -0.16256 -0.76835) (xy -0.1651 -0.7366) (xy -0.1651 0.13462)
						(xy -0.17272 0.14224) (xy -0.19812 0.1778) (xy -0.2032 0.18796) (xy -0.20701 0.19685) (xy -0.21209 0.20701)
						(xy -0.2159 0.21717) (xy -0.21844 0.22733) (xy -0.22225 0.23876) (xy -0.22352 0.24892) (xy -0.22606 0.25908)
						(xy -0.22733 0.27051) (xy -0.22733 0.28067) (xy -0.2286 0.2921) (xy -0.22733 0.30353) (xy -0.22733 0.31369)
						(xy -0.22606 0.32512) (xy -0.22352 0.33528) (xy -0.22225 0.34544) (xy -0.21844 0.35687) (xy -0.2159 0.36703)
						(xy -0.21209 0.37719) (xy -0.20701 0.38735) (xy -0.2032 0.39624) (xy -0.19812 0.4064) (xy -0.17272 0.44196)
						(xy -0.1651 0.44958) (xy -0.1651 0.7366) (xy -0.16256 0.76835) (xy -0.1524 0.8001) (xy -0.13716 0.82804)
						(xy -0.11684 0.85344) (xy -0.09144 0.87376) (xy -0.0635 0.889) (xy -0.03175 0.89916) (xy 0 0.9017)
						(xy 0.03175 0.89916) (xy 0.0635 0.889) (xy 0.09144 0.87376) (xy 0.11684 0.85344) (xy 0.13716 0.82804)
						(xy 0.1524 0.8001) (xy 0.16256 0.76835) (xy 0.1651 0.7366) (xy 0.1651 0.44958) (xy 0.17272 0.44196)
						(xy 0.19812 0.4064) (xy 0.2032 0.39624) (xy 0.20701 0.38735) (xy 0.21209 0.37719) (xy 0.2159 0.36703)
						(xy 0.21844 0.35687) (xy 0.22225 0.34544) (xy 0.22352 0.33528) (xy 0.22606 0.32512) (xy 0.22733 0.31369)
						(xy 0.22733 0.30353) (xy 0.2286 0.2921) (xy 0.22733 0.28067) (xy 0.22733 0.27051) (xy 0.22606 0.25908)
						(xy 0.22352 0.24892) (xy 0.22225 0.23876) (xy 0.21844 0.22733) (xy 0.2159 0.21717) (xy 0.21209 0.20701)
						(xy 0.20701 0.19685) (xy 0.2032 0.18796) (xy 0.19812 0.1778) (xy 0.17272 0.14224) (xy 0.1651 0.13462)
						(xy 0.1651 -0.7366) (xy 0.16256 -0.76835) (xy 0.1524 -0.8001) (xy 0.13716 -0.82804) (xy 0.11684 -0.85344)
						(xy 0.09144 -0.87376) (xy 0.0635 -0.889) (xy 0.03175 -0.89916)
					)
					(width 0)
					(fill yes)
				)
			)
		)
	)
)
